# BASEBOARD_FAB2 (Tioga Pass) — schematic netlist excerpt (pin names and nets, part order shuffled) for the footprints in the layout excerpt that follows; sources: Cadence DE-HDL packaged netlist, KiCad conversion of Wiwynn_Tioga_Pass_MB.brd

J6M1  SCONN288_H44441003  SCONN  pkg PIP  page 50
  \12v\(1)  = P12V_NVDIMM_DEF
  VSS(93)  = GND
  DQ(4)  = M_D_DQ<4>
  VSS(92)  = GND
  DQ(0)  = M_D_DQ<0>
  VSS(91)  = GND
  DQS9P  = M_D_DQS_DP<9>
  DQS9N  = M_D_DQS_DN<9>
  VSS(90)  = GND
  DQ(6)  = M_D_DQ<6>
  VSS(89)  = GND
  DQ(2)  = M_D_DQ<2>
  VSS(88)  = GND
  DQ(12)  = M_D_DQ<12>
  VSS(87)  = GND
  DQ(8)  = M_D_DQ<8>
  VSS(86)  = GND
  DQS10P  = M_D_DQS_DP<10>
  DQS10N  = M_D_DQS_DN<10>
  VSS(85)  = GND
  DQ(14)  = M_D_DQ<14>
  VSS(84)  = GND
  DQ(10)  = M_D_DQ<10>
  VSS(83)  = GND
  DQ(20)  = M_D_DQ<20>
  VSS(82)  = GND
  DQ(16)  = M_D_DQ<16>
  VSS(81)  = GND
  DQS11P  = M_D_DQS_DP<11>
  DQS11N  = M_D_DQS_DN<11>
  VSS(80)  = GND
  DQ(22)  = M_D_DQ<22>
  VSS(79)  = GND
  DQ(18)  = M_D_DQ<18>
  VSS(78)  = GND
  DQ(28)  = M_D_DQ<28>
  VSS(77)  = GND
  DQ(24)  = M_D_DQ<24>
  VSS(76)  = GND
  DQS12P  = M_D_DQS_DP<12>
  DQS12N  = M_D_DQS_DN<12>
  VSS(75)  = GND
  DQ(30)  = M_D_DQ<30>
  VSS(74)  = GND
  DQ(26)  = M_D_DQ<26>
  VSS(73)  = GND
  CB(4)  = M_D_ECC<4>
  VSS(72)  = GND
  CB(0)  = M_D_ECC<0>
  VSS(71)  = GND
  DQS17P  = M_D_DQS_DP<17>
  DQS17N  = M_D_DQS_DN<17>
  VSS(70)  = GND
  CB(6)  = M_D_ECC<6>
  VSS(69)  = GND
  CB(2)  = M_D_ECC<2>
  VSS(68)  = GND
  RESET_N  = M_DEF_RST_N
  VDD(25)  = PVDDQ_DEF
  CKE(0)  = M_D_CKE<2>
  VDD(24)  = PVDDQ_DEF
  ACT_N  = M_D_ACT_N
  BG(0)  = M_D_BG<0>
  VDD(23)  = PVDDQ_DEF
  A12  = M_D_MA<12>
  A9  = M_D_MA<9>
  VDD(22)  = PVDDQ_DEF
  A8  = M_D_MA<8>
  A6  = M_D_MA<6>
  VDD(21)  = PVDDQ_DEF
  A3  = M_D_MA<3>
  A1  = M_D_MA<1>
  VDD(20)  = PVDDQ_DEF
  CK0P  = M_D_CLK_DP<2>
  CK0N  = M_D_CLK_DN<2>
  VDD(19)  = PVDDQ_DEF
  VTT(1)  = PVTT_DEF
  EVENT_N  = FM_DIMM_EVENT_COD_N
  A0  = M_D_MA<0>
  VDD(18)  = PVDDQ_DEF
  BA(0)  = M_D_BA<0>
  A16_RAS_N  = M_D_MA<16>
  VDD(17)  = PVDDQ_DEF
  S0_N  = M_D_CS_N<4>
  VDD(16)  = PVDDQ_DEF
  A15_CAS_N  = M_D_MA<15>
  ODT(0)  = M_D_ODT<2>
  VDD(15)  = PVDDQ_DEF
  S1_N  = M_D_CS_N<5>
  VDD(14)  = PVDDQ_DEF
  ODT(1)  = M_D_ODT<3>
  VDD(13)  = PVDDQ_DEF
  S2_N_C(0)  = M_D_CS_N<6>
  VSS(67)  = GND
  DQ(36)  = M_D_DQ<36>
  VSS(66)  = GND
  DQ(32)  = M_D_DQ<32>
  VSS(65)  = GND
  DQS13P  = M_D_DQS_DP<13>
  DQS13N  = M_D_DQS_DN<13>
  VSS(64)  = GND
  DQ(38)  = M_D_DQ<38>
  VSS(63)  = GND
  DQ(34)  = M_D_DQ<34>
  VSS(62)  = GND
  DQ(44)  = M_D_DQ<44>
  VSS(61)  = GND
  DQ(40)  = M_D_DQ<40>
  VSS(60)  = GND
  DQS14P  = M_D_DQS_DP<14>
  DQS14N  = M_D_DQS_DN<14>
  VSS(59)  = GND
  DQ(46)  = M_D_DQ<46>
  VSS(58)  = GND
  DQ(42)  = M_D_DQ<42>
  VSS(57)  = GND
  DQ(52)  = M_D_DQ<52>
  VSS(56)  = GND
  DQ(48)  = M_D_DQ<48>
  VSS(55)  = GND
  DQS15P  = M_D_DQS_DP<15>
  DQS15N  = M_D_DQS_DN<15>
  VSS(54)  = GND
  DQ(54)  = M_D_DQ<54>
  VSS(53)  = GND
  DQ(50)  = M_D_DQ<50>
  VSS(52)  = GND
  DQ(60)  = M_D_DQ<60>
  VSS(51)  = GND
  DQ(56)  = M_D_DQ<56>
  VSS(50)  = GND
  DQS16P  = M_D_DQS_DP<16>
  DQS16N  = M_D_DQS_DN<16>
  VSS(49)  = GND
  DQ(62)  = M_D_DQ<62>
  VSS(48)  = GND
  DQ(58)  = M_D_DQ<58>
  VSS(47)  = GND
  SA(0)  = PVPP_DEF
  SA(1)  = GND
  SCL  = SMB_DDR_DEF_VPP_SCL
  VPP(4)  = PVPP_DEF
  VPP(3)  = PVPP_DEF
  RFU(2)  = TP_CH_D_DIMM_D1_RFU_2
  \12v\(0)  = P12V_NVDIMM_DEF
  VREFCA  = M_D_VREF
  VSS(46)  = GND
  DQ(5)  = M_D_DQ<5>
  VSS(45)  = GND
  DQ(1)  = M_D_DQ<1>
  VSS(44)  = GND
  DQS0N  = M_D_DQS_DN<0>
  DQS0P  = M_D_DQS_DP<0>
  VSS(43)  = GND
  DQ(7)  = M_D_DQ<7>
  VSS(42)  = GND
  DQ(3)  = M_D_DQ<3>
  VSS(41)  = GND
  DQ(13)  = M_D_DQ<13>
  VSS(40)  = GND
  DQ(9)  = M_D_DQ<9>
  VSS(39)  = GND
  DQS1N  = M_D_DQS_DN<1>
  DQS1P  = M_D_DQS_DP<1>
  VSS(38)  = GND
  DQ(15)  = M_D_DQ<15>
  VSS(37)  = GND
  DQ(11)  = M_D_DQ<11>
  VSS(36)  = GND
  DQ(21)  = M_D_DQ<21>
  VSS(35)  = GND
  DQ(17)  = M_D_DQ<17>
  VSS(34)  = GND
  DQS2N  = M_D_DQS_DN<2>
  DQS2P  = M_D_DQS_DP<2>
  VSS(33)  = GND
  DQ(23)  = M_D_DQ<23>
  VSS(32)  = GND
  DQ(19)  = M_D_DQ<19>
  VSS(31)  = GND
  DQ(29)  = M_D_DQ<29>
  VSS(30)  = GND
  DQ(25)  = M_D_DQ<25>
  VSS(29)  = GND
  DQS3N  = M_D_DQS_DN<3>
  DQS3P  = M_D_DQS_DP<3>
  VSS(28)  = GND
  DQ(31)  = M_D_DQ<31>
  VSS(27)  = GND
  DQ(27)  = M_D_DQ<27>
  VSS(26)  = GND
  CB(5)  = M_D_ECC<5>
  VSS(25)  = GND
  CB(1)  = M_D_ECC<1>
  VSS(24)  = GND
  DQS8N  = M_D_DQS_DN<8>
  DQS8P  = M_D_DQS_DP<8>
  VSS(23)  = GND
  CB(7)  = M_D_ECC<7>
  VSS(22)  = GND
  CB(3)  = M_D_ECC<3>
  VSS(21)  = GND
  CKE(1)  = M_D_CKE<3>
  VDD(12)  = PVDDQ_DEF
  RFU(0)  = TP_CH_D_DIMM_D1_RFU_0
  VDD(11)  = PVDDQ_DEF
  BG(1)  = M_D_BG<1>
  ALERT_N  = M_D_ALERT_N
  VDD(10)  = PVDDQ_DEF
  A11  = M_D_MA<11>
  A7  = M_D_MA<7>
  VDD(9)  = PVDDQ_DEF
  A5  = M_D_MA<5>
  A4  = M_D_MA<4>
  VDD(8)  = PVDDQ_DEF
  A2  = M_D_MA<2>
  VDD(7)  = PVDDQ_DEF
  CK1P  = M_D_CLK_DP<3>
  CK1N  = M_D_CLK_DN<3>
  VDD(6)  = PVDDQ_DEF
  VTT(0)  = PVTT_DEF
  PAR  = M_D_PAR
  VDD(5)  = PVDDQ_DEF
  BA(1)  = M_D_BA<1>
  A10  = M_D_MA<10>
  VDD(4)  = PVDDQ_DEF
  RFU(1)  = TP_CH_D_DIMM_D1_RFU_1
  A14_WE_N  = M_D_MA<14>
  VDD(3)  = PVDDQ_DEF
  SAVE_N_NC  = FM_ADR_COMPLETE_DEF_N
  VDD(2)  = PVDDQ_DEF
  A13  = M_D_MA<13>
  VDD(1)  = PVDDQ_DEF
  A17  = M_D_MA<17>
  C(2)  = M_D_C<2>
  VDD(0)  = PVDDQ_DEF
  S3_N_C(1)  = M_D_CS_N<7>
  SA(2)  = GND
  VSS(20)  = GND
  DQ(37)  = M_D_DQ<37>
  VSS(19)  = GND
  DQ(33)  = M_D_DQ<33>
  VSS(18)  = GND
  DQS4N  = M_D_DQS_DN<4>
  DQS4P  = M_D_DQS_DP<4>
  VSS(17)  = GND
  DQ(39)  = M_D_DQ<39>
  VSS(16)  = GND
  DQ(35)  = M_D_DQ<35>
  VSS(15)  = GND
  DQ(45)  = M_D_DQ<45>
  VSS(14)  = GND
  DQ(41)  = M_D_DQ<41>
  VSS(13)  = GND
  DQS5N  = M_D_DQS_DN<5>
  DQS5P  = M_D_DQS_DP<5>
  VSS(12)  = GND
  DQ(47)  = M_D_DQ<47>
  VSS(11)  = GND
  DQ(43)  = M_D_DQ<43>
  VSS(10)  = GND
  DQ(53)  = M_D_DQ<53>
  VSS(9)  = GND
  DQ(49)  = M_D_DQ<49>
  VSS(8)  = GND
  DQS6N  = M_D_DQS_DN<6>
  DQS6P  = M_D_DQS_DP<6>
  VSS(7)  = GND
  DQ(55)  = M_D_DQ<55>
  VSS(6)  = GND
  DQ(51)  = M_D_DQ<51>
  VSS(5)  = GND
  DQ(61)  = M_D_DQ<61>
  VSS(4)  = GND
  DQ(57)  = M_D_DQ<57>
  VSS(3)  = GND
  DQS7N  = M_D_DQS_DN<7>
  DQS7P  = M_D_DQS_DP<7>
  VSS(2)  = GND
  DQ(63)  = M_D_DQ<63>
  VSS(1)  = GND
  DQ(59)  = M_D_DQ<59>
  VSS(0)  = GND
  VDDSPD  = PVPP_DEF
  SDA  = SMB_DDR_DEF_VPP_SDA
  VPP(1)  = PVPP_DEF
  VPP(0)  = PVPP_DEF
  VPP(2)  = PVPP_DEF

(kicad_pcb
	(version 20260206)
	(generator "pcbnew")
	(generator_version "10.0")
	(general
		(thickness 1.6)
		(legacy_teardrops no)
	)
	(paper "A4")
	(title_block
		(title "Wiwynn_Tioga_Pass_MB.brd")
		(comment 1 "Tioga Pass / footprint 3254 of 4770 (J6M1), pads 152-201 of 291")
	)
	(layers
		(0 "F.Cu" signal "TOP")
		(4 "In1.Cu" signal "L2GND")
		(6 "In2.Cu" signal "L3")
		(8 "In3.Cu" signal "L4GND")
		(10 "In4.Cu" signal "L5")
		(12 "In5.Cu" signal "L6GND")
		(14 "In6.Cu" signal "L7VCC")
		(16 "In7.Cu" signal "L8VCC")
		(18 "In8.Cu" signal "L9GND")
		(20 "In9.Cu" signal "L10")
		(22 "In10.Cu" signal "L11GND")
		(24 "In11.Cu" signal "L12")
		(26 "In12.Cu" signal "L13GND")
		(2 "B.Cu" signal "BOTTOM")
		(9 "F.Adhes" user "F.Adhesive")
		(11 "B.Adhes" user "B.Adhesive")
		(13 "F.Paste" user "Package Geometry/Pastemask Top")
		(15 "B.Paste" user "Package Geometry/Pastemask Bottom")
		(5 "F.SilkS" user "Ref Des/Silkscreen Top")
		(7 "B.SilkS" user "Ref Des/Silkscreen Bottom")
		(1 "F.Mask" user "Board Geometry/Soldermask Top")
		(3 "B.Mask" user "Board Geometry/Soldermask Bottom")
		(17 "Dwgs.User" user "User.Drawings")
		(19 "Cmts.User" user "User.Comments")
		(21 "Eco1.User" user "User.Eco1")
		(23 "Eco2.User" user "User.Eco2")
		(25 "Edge.Cuts" user "Board Geometry/Outline")
		(27 "Margin" user)
		(31 "F.CrtYd" user "Package Geometry/Place Bound Top")
		(29 "B.CrtYd" user "Package Geometry/Place Bound Bottom")
		(35 "F.Fab" user "Ref Des/Assembly Top")
		(33 "B.Fab" user "Ref Des/Assembly Bottom")
	)
	(footprint ""
		(layer "B.Cu")
		(at 194.700398 -132.876036 90)
		(property "Reference" "J6M1"
			(at 2.352548 37.96411 0)
			(unlocked yes)
			(layer "B.SilkS")
			(effects
				(font
					(size 0.7874 0.5842)
					(thickness 0.1524)
				)
				(justify left mirror)
			)
		)
		(property "Value" ""
			(at 0 0 90)
			(layer "B.Fab")
			(effects
				(font
					(size 1.27 1.27)
				)
				(justify mirror)
			)
		)
		(duplicate_pad_numbers_are_jumpers no)
		(pad "149" smd rect
			(at -4.59994 3.400044 270)
			(size 1.8034 0.508)
			(layers "B.Cu" "B.Mask" "B.Paste")
			(net "GND")
		)
		(pad "150" smd rect
			(at -4.59994 4.249928 270)
			(size 1.8034 0.508)
			(layers "B.Cu" "B.Mask" "B.Paste")
			(net "M_D_DQ<1>")
		)
		(pad "151" smd rect
			(at -4.59994 5.100066 270)
			(size 1.8034 0.508)
			(layers "B.Cu" "B.Mask" "B.Paste")
			(net "GND")
		)
		(pad "152" smd rect
			(at -4.59994 5.94995 270)
			(size 1.8034 0.508)
			(layers "B.Cu" "B.Mask" "B.Paste")
			(net "M_D_DQS_DN<0>")
		)
		(pad "153" smd rect
			(at -4.59994 6.800088 270)
			(size 1.8034 0.508)
			(layers "B.Cu" "B.Mask" "B.Paste")
			(net "M_D_DQS_DP<0>")
		)
		(pad "154" smd rect
			(at -4.59994 7.649972 270)
			(size 1.8034 0.508)
			(layers "B.Cu" "B.Mask" "B.Paste")
			(net "GND")
		)
		(pad "155" smd rect
			(at -4.59994 8.50011 270)
			(size 1.8034 0.508)
			(layers "B.Cu" "B.Mask" "B.Paste")
			(net "M_D_DQ<7>")
		)
		(pad "156" smd rect
			(at -4.59994 9.349994 270)
			(size 1.8034 0.508)
			(layers "B.Cu" "B.Mask" "B.Paste")
			(net "GND")
		)
		(pad "157" smd rect
			(at -4.59994 10.199878 270)
			(size 1.8034 0.508)
			(layers "B.Cu" "B.Mask" "B.Paste")
			(net "M_D_DQ<3>")
		)
		(pad "158" smd rect
			(at -4.59994 11.050016 270)
			(size 1.8034 0.508)
			(layers "B.Cu" "B.Mask" "B.Paste")
			(net "GND")
		)
		(pad "159" smd rect
			(at -4.59994 11.8999 270)
			(size 1.8034 0.508)
			(layers "B.Cu" "B.Mask" "B.Paste")
			(net "M_D_DQ<13>")
		)
		(pad "160" smd rect
			(at -4.59994 12.750038 270)
			(size 1.8034 0.508)
			(layers "B.Cu" "B.Mask" "B.Paste")
			(net "GND")
		)
		(pad "161" smd rect
			(at -4.59994 13.599922 270)
			(size 1.8034 0.508)
			(layers "B.Cu" "B.Mask" "B.Paste")
			(net "M_D_DQ<9>")
		)
		(pad "162" smd rect
			(at -4.59994 14.45006 270)
			(size 1.8034 0.508)
			(layers "B.Cu" "B.Mask" "B.Paste")
			(net "GND")
		)
		(pad "163" smd rect
			(at -4.59994 15.299944 270)
			(size 1.8034 0.508)
			(layers "B.Cu" "B.Mask" "B.Paste")
			(net "M_D_DQS_DN<1>")
		)
		(pad "164" smd rect
			(at -4.59994 16.150082 270)
			(size 1.8034 0.508)
			(layers "B.Cu" "B.Mask" "B.Paste")
			(net "M_D_DQS_DP<1>")
		)
		(pad "165" smd rect
			(at -4.59994 16.999966 270)
			(size 1.8034 0.508)
			(layers "B.Cu" "B.Mask" "B.Paste")
			(net "GND")
		)
		(pad "166" smd rect
			(at -4.59994 17.850104 270)
			(size 1.8034 0.508)
			(layers "B.Cu" "B.Mask" "B.Paste")
			(net "M_D_DQ<15>")
		)
		(pad "167" smd rect
			(at -4.59994 18.699988 270)
			(size 1.8034 0.508)
			(layers "B.Cu" "B.Mask" "B.Paste")
			(net "GND")
		)
		(pad "168" smd rect
			(at -4.59994 19.550126 270)
			(size 1.8034 0.508)
			(layers "B.Cu" "B.Mask" "B.Paste")
			(net "M_D_DQ<11>")
		)
		(pad "169" smd rect
			(at -4.59994 20.40001 270)
			(size 1.8034 0.508)
			(layers "B.Cu" "B.Mask" "B.Paste")
			(net "GND")
		)
		(pad "170" smd rect
			(at -4.59994 21.249894 270)
			(size 1.8034 0.508)
			(layers "B.Cu" "B.Mask" "B.Paste")
			(net "M_D_DQ<21>")
		)
		(pad "171" smd rect
			(at -4.59994 22.100032 270)
			(size 1.8034 0.508)
			(layers "B.Cu" "B.Mask" "B.Paste")
			(net "GND")
		)
		(pad "172" smd rect
			(at -4.59994 22.949916 270)
			(size 1.8034 0.508)
			(layers "B.Cu" "B.Mask" "B.Paste")
			(net "M_D_DQ<17>")
		)
		(pad "173" smd rect
			(at -4.59994 23.800054 270)
			(size 1.8034 0.508)
			(layers "B.Cu" "B.Mask" "B.Paste")
			(net "GND")
		)
		(pad "174" smd rect
			(at -4.59994 24.649938 270)
			(size 1.8034 0.508)
			(layers "B.Cu" "B.Mask" "B.Paste")
			(net "M_D_DQS_DN<2>")
		)
		(pad "175" smd rect
			(at -4.59994 25.500076 270)
			(size 1.8034 0.508)
			(layers "B.Cu" "B.Mask" "B.Paste")
			(net "M_D_DQS_DP<2>")
		)
		(pad "176" smd rect
			(at -4.59994 26.34996 270)
			(size 1.8034 0.508)
			(layers "B.Cu" "B.Mask" "B.Paste")
			(net "GND")
		)
		(pad "177" smd rect
			(at -4.59994 27.200098 270)
			(size 1.8034 0.508)
			(layers "B.Cu" "B.Mask" "B.Paste")
			(net "M_D_DQ<23>")
		)
		(pad "178" smd rect
			(at -4.59994 28.049982 270)
			(size 1.8034 0.508)
			(layers "B.Cu" "B.Mask" "B.Paste")
			(net "GND")
		)
		(pad "179" smd rect
			(at -4.59994 28.90012 270)
			(size 1.8034 0.508)
			(layers "B.Cu" "B.Mask" "B.Paste")
			(net "M_D_DQ<19>")
		)
		(pad "180" smd rect
			(at -4.59994 29.750004 270)
			(size 1.8034 0.508)
			(layers "B.Cu" "B.Mask" "B.Paste")
			(net "GND")
		)
		(pad "181" smd rect
			(at -4.59994 30.599888 270)
			(size 1.8034 0.508)
			(layers "B.Cu" "B.Mask" "B.Paste")
			(net "M_D_DQ<29>")
		)
		(pad "182" smd rect
			(at -4.59994 31.450026 270)
			(size 1.8034 0.508)
			(layers "B.Cu" "B.Mask" "B.Paste")
			(net "GND")
		)
		(pad "183" smd rect
			(at -4.59994 32.29991 270)
			(size 1.8034 0.508)
			(layers "B.Cu" "B.Mask" "B.Paste")
			(net "M_D_DQ<25>")
		)
		(pad "184" smd rect
			(at -4.59994 33.150048 270)
			(size 1.8034 0.508)
			(layers "B.Cu" "B.Mask" "B.Paste")
			(net "GND")
		)
		(pad "185" smd rect
			(at -4.59994 33.999932 270)
			(size 1.8034 0.508)
			(layers "B.Cu" "B.Mask" "B.Paste")
			(net "M_D_DQS_DN<3>")
		)
		(pad "186" smd rect
			(at -4.59994 34.85007 270)
			(size 1.8034 0.508)
			(layers "B.Cu" "B.Mask" "B.Paste")
			(net "M_D_DQS_DP<3>")
		)
		(pad "187" smd rect
			(at -4.59994 35.699954 270)
			(size 1.8034 0.508)
			(layers "B.Cu" "B.Mask" "B.Paste")
			(net "GND")
		)
		(pad "188" smd rect
			(at -4.59994 36.550092 270)
			(size 1.8034 0.508)
			(layers "B.Cu" "B.Mask" "B.Paste")
			(net "M_D_DQ<31>")
		)
		(pad "189" smd rect
			(at -4.59994 37.399976 270)
			(size 1.8034 0.508)
			(layers "B.Cu" "B.Mask" "B.Paste")
			(net "GND")
		)
		(pad "190" smd rect
			(at -4.59994 38.250114 270)
			(size 1.8034 0.508)
			(layers "B.Cu" "B.Mask" "B.Paste")
			(net "M_D_DQ<27>")
		)
		(pad "191" smd rect
			(at -4.59994 39.099998 270)
			(size 1.8034 0.508)
			(layers "B.Cu" "B.Mask" "B.Paste")
			(net "GND")
		)
		(pad "192" smd rect
			(at -4.59994 39.949882 270)
			(size 1.8034 0.508)
			(layers "B.Cu" "B.Mask" "B.Paste")
			(net "M_D_ECC<5>")
		)
		(pad "193" smd rect
			(at -4.59994 40.80002 270)
			(size 1.8034 0.508)
			(layers "B.Cu" "B.Mask" "B.Paste")
			(net "GND")
		)
		(pad "194" smd rect
			(at -4.59994 41.649904 270)
			(size 1.8034 0.508)
			(layers "B.Cu" "B.Mask" "B.Paste")
			(net "M_D_ECC<1>")
		)
		(pad "195" smd rect
			(at -4.59994 42.500042 270)
			(size 1.8034 0.508)
			(layers "B.Cu" "B.Mask" "B.Paste")
			(net "GND")
		)
		(pad "196" smd rect
			(at -4.59994 43.349926 270)
			(size 1.8034 0.508)
			(layers "B.Cu" "B.Mask" "B.Paste")
			(net "M_D_DQS_DN<8>")
		)
		(pad "197" smd rect
			(at -4.59994 44.200064 270)
			(size 1.8034 0.508)
			(layers "B.Cu" "B.Mask" "B.Paste")
			(net "M_D_DQS_DP<8>")
		)
		(pad "198" smd rect
			(at -4.59994 45.049948 270)
			(size 1.8034 0.508)
			(layers "B.Cu" "B.Mask" "B.Paste")
			(net "GND")
		)
	)
)
